# S9S_MB_2U (Grand Teton) — schematic netlist excerpt (pin names and nets, part order shuffled) for the footprints in the layout excerpt that follows; sources: Cadence DE-HDL packaged netlist, KiCad conversion of 03242023_DA0F0TMBIJ0_F0T_Motherboard_J_brd_V01_OCP.brd

PJ67  Q_SHORT  EMPTY  pkg SM  page 299 : \1\ = SH_PVPP_HBM_CPU1_N ; \2\ = GND
R2500  Q_RES  33.2 1% CHIP  pkg 0402LF  page 115 : A = PWRGD_FAIL_CPU0_EF_R1 ; B = PWRGD_FAIL_CPU0_EF_R
C1258  Q_CAP  47UF 4V 20% X6S  pkg C0805  page 189 : A = P1V05_PCH_PLL_AUX ; B = GND

(kicad_pcb
	(version 20260206)
	(generator "pcbnew")
	(generator_version "10.0")
	(general
		(thickness 1.6)
		(legacy_teardrops no)
	)
	(paper "A4")
	(title_block
		(title "03242023_DA0F0TMBIJ0_F0T_Motherboard_J_brd_V01_OCP.brd")
		(comment 1 "Grand Teton / footprints 5936-5938 of 6105")
	)
	(layers
		(0 "F.Cu" signal "TOP")
		(4 "In1.Cu" signal "GND")
		(6 "In2.Cu" signal "IN1")
		(8 "In3.Cu" signal "GND1")
		(10 "In4.Cu" signal "IN2")
		(12 "In5.Cu" signal "GND2")
		(14 "In6.Cu" signal "IN3")
		(16 "In7.Cu" signal "GND3")
		(18 "In8.Cu" signal "VCC")
		(20 "In9.Cu" signal "VCC1")
		(22 "In10.Cu" signal "GND4")
		(24 "In11.Cu" signal "IN4")
		(26 "In12.Cu" signal "GND5")
		(28 "In13.Cu" signal "IN5")
		(30 "In14.Cu" signal "GND6")
		(32 "In15.Cu" signal "IN6")
		(34 "In16.Cu" signal "GND7")
		(2 "B.Cu" signal "BOTTOM")
		(9 "F.Adhes" user "F.Adhesive")
		(11 "B.Adhes" user "B.Adhesive")
		(13 "F.Paste" user "Package Geometry/Pastemask Top")
		(15 "B.Paste" user "Package Geometry/Pastemask Bottom")
		(5 "F.SilkS" user "Ref Des/Silkscreen Top")
		(7 "B.SilkS" user "Ref Des/Silkscreen Bottom")
		(1 "F.Mask" user "Board Geometry/Soldermask Top")
		(3 "B.Mask" user "Board Geometry/Soldermask Bottom")
		(17 "Dwgs.User" user "User.Drawings")
		(19 "Cmts.User" user "User.Comments")
		(21 "Eco1.User" user "User.Eco1")
		(23 "Eco2.User" user "User.Eco2")
		(25 "Edge.Cuts" user "Board Geometry/Outline")
		(27 "Margin" user)
		(31 "F.CrtYd" user "Package Geometry/Place Bound Top")
		(29 "B.CrtYd" user "Package Geometry/Place Bound Bottom")
		(35 "F.Fab" user "Ref Des/Assembly Top")
		(33 "B.Fab" user "Ref Des/Assembly Bottom")
	)
	(footprint ""
		(layer "B.Cu")
		(at 433.077366 -311.86374 90)
		(property "Reference" "R2500"
			(at 0 0 90)
			(layer "B.SilkS")
			(hide yes)
			(effects
				(font
					(size 1.27 1.27)
				)
				(justify mirror)
			)
		)
		(property "Value" ""
			(at 0 0 90)
			(layer "B.Fab")
			(effects
				(font
					(size 1.27 1.27)
				)
				(justify mirror)
			)
		)
		(duplicate_pad_numbers_are_jumpers no)
		(fp_line
			(start 0.7874 -0.4064)
			(end -0.7874 -0.4064)
			(stroke
				(width 0.1524)
				(type default)
			)
			(layer "B.SilkS")
		)
		(fp_line
			(start -0.7874 -0.4064)
			(end -0.7874 0.4064)
			(stroke
				(width 0.1524)
				(type default)
			)
			(layer "B.SilkS")
		)
		(fp_line
			(start 0.7874 0.4064)
			(end 0.7874 -0.4064)
			(stroke
				(width 0.1524)
				(type default)
			)
			(layer "B.SilkS")
		)
		(fp_line
			(start -0.7874 0.4064)
			(end 0.7874 0.4064)
			(stroke
				(width 0.1524)
				(type default)
			)
			(layer "B.SilkS")
		)
		(fp_line
			(start 0.67945 -0.305054)
			(end 0.12065 -0.305054)
			(stroke
				(width 0.1)
				(type default)
			)
			(layer "B.Fab")
		)
		(fp_line
			(start 0.12065 -0.305054)
			(end 0.12065 -0.2794)
			(stroke
				(width 0.1)
				(type default)
			)
			(layer "B.Fab")
		)
		(fp_line
			(start -0.12065 -0.3048)
			(end -0.67945 -0.3048)
			(stroke
				(width 0.1)
				(type default)
			)
			(layer "B.Fab")
		)
		(fp_line
			(start -0.67945 -0.3048)
			(end -0.67945 0.3048)
			(stroke
				(width 0.1)
				(type default)
			)
			(layer "B.Fab")
		)
		(fp_line
			(start 0.12065 -0.2794)
			(end -0.12065 -0.2794)
			(stroke
				(width 0.1)
				(type default)
			)
			(layer "B.Fab")
		)
		(fp_line
			(start -0.12065 -0.2794)
			(end -0.12065 -0.3048)
			(stroke
				(width 0.1)
				(type default)
			)
			(layer "B.Fab")
		)
		(fp_line
			(start 0.12065 0.2794)
			(end 0.12065 0.3048)
			(stroke
				(width 0.1)
				(type default)
			)
			(layer "B.Fab")
		)
		(fp_line
			(start -0.120396 0.2794)
			(end 0.12065 0.2794)
			(stroke
				(width 0.1)
				(type default)
			)
			(layer "B.Fab")
		)
		(fp_line
			(start 0.67945 0.3048)
			(end 0.67945 -0.305054)
			(stroke
				(width 0.1)
				(type default)
			)
			(layer "B.Fab")
		)
		(fp_line
			(start 0.12065 0.3048)
			(end 0.67945 0.3048)
			(stroke
				(width 0.1)
				(type default)
			)
			(layer "B.Fab")
		)
		(fp_line
			(start -0.120396 0.3048)
			(end -0.120396 0.2794)
			(stroke
				(width 0.1)
				(type default)
			)
			(layer "B.Fab")
		)
		(fp_line
			(start -0.67945 0.3048)
			(end -0.120396 0.3048)
			(stroke
				(width 0.1)
				(type default)
			)
			(layer "B.Fab")
		)
		(pad "1" smd circle
			(at 0.40005 0 270)
			(size 0 0)
			(layers "B.Cu" "B.Mask" "B.Paste")
			(net "PWRGD_FAIL_CPU0_EF_R1")
		)
		(pad "2" smd circle
			(at -0.40005 0 270)
			(size 0 0)
			(layers "B.Cu" "B.Mask" "B.Paste")
			(net "PWRGD_FAIL_CPU0_EF_R")
		)
	)
	(footprint ""
		(layer "B.Cu")
		(at 331.312774 -63.123064 45)
		(property "Reference" "C1258"
			(at 0 0 45)
			(layer "B.SilkS")
			(hide yes)
			(effects
				(font
					(size 1.27 1.27)
				)
				(justify mirror)
			)
		)
		(property "Value" ""
			(at 0 0 45)
			(layer "B.Fab")
			(effects
				(font
					(size 1.27 1.27)
				)
				(justify mirror)
			)
		)
		(duplicate_pad_numbers_are_jumpers no)
		(fp_line
			(start -1.523949 -0.762065)
			(end -1.523949 0.762065)
			(stroke
				(width 0.1524)
				(type default)
			)
			(layer "B.SilkS")
		)
		(fp_line
			(start -1.523949 0.762065)
			(end 1.523949 0.762065)
			(stroke
				(width 0.1524)
				(type default)
			)
			(layer "B.SilkS")
		)
		(fp_line
			(start 1.523949 -0.762065)
			(end -1.523949 -0.762065)
			(stroke
				(width 0.1524)
				(type default)
			)
			(layer "B.SilkS")
		)
		(fp_line
			(start 1.523949 0.762065)
			(end 1.523949 -0.762065)
			(stroke
				(width 0.1524)
				(type default)
			)
			(layer "B.SilkS")
		)
		(fp_line
			(start -1.104931 -0.724886)
			(end 1.104931 -0.724886)
			(stroke
				(width 0.1)
				(type default)
			)
			(layer "B.Fab")
		)
		(fp_line
			(start -1.104931 0.724886)
			(end -1.104931 -0.724886)
			(stroke
				(width 0.1)
				(type default)
			)
			(layer "B.Fab")
		)
		(fp_line
			(start 1.104931 -0.724886)
			(end 1.104931 0.724886)
			(stroke
				(width 0.1)
				(type default)
			)
			(layer "B.Fab")
		)
		(fp_line
			(start 1.104931 0.724886)
			(end -1.104931 0.724886)
			(stroke
				(width 0.1)
				(type default)
			)
			(layer "B.Fab")
		)
		(pad "1" smd rect
			(at 0.889 0 45)
			(size 1.016 1.27)
			(layers "B.Cu" "B.Mask" "B.Paste")
			(net "P1V05_PCH_PLL_AUX")
		)
		(pad "2" smd rect
			(at -0.889 0 45)
			(size 1.016 1.27)
			(layers "B.Cu" "B.Mask" "B.Paste")
			(net "GND")
		)
	)
	(footprint ""
		(layer "B.Cu")
		(at 121.830084 -359.596436 -90)
		(property "Reference" "PJ67"
			(at -4.219702 -2.927096 0)
			(unlocked yes)
			(layer "B.SilkS")
			(effects
				(font
					(size 0.7874 0.5842)
					(thickness 0.1524)
				)
				(justify left mirror)
			)
		)
		(property "Value" ""
			(at 0 0 90)
			(layer "B.Fab")
			(effects
				(font
					(size 1.27 1.27)
				)
				(justify mirror)
			)
		)
		(duplicate_pad_numbers_are_jumpers no)
		(pad "1" smd circle
			(at 0.7493 0)
			(size 0 0)
			(layers "B.Cu" "B.Mask" "B.Paste")
			(net "SH_PVPP_HBM_CPU1_N")
		)
		(pad "2" smd rect
			(at -0.7493 0 180)
			(size 0.7112 0.8128)
			(layers "B.Cu" "B.Mask" "B.Paste")
			(net "GND")
		)
		(zone
			(layer "B.Cu")
			(hatch none 0.5)
			(connect_pads
				(clearance 0)
			)
			(min_thickness 0.25)
			(keepout
				(tracks allowed)
				(vias not_allowed)
				(pads allowed)
				(copperpour not_allowed)
				(footprints allowed)
			)
			(placement
				(enabled no)
				(sheetname "")
			)
			(fill
				(thermal_gap 0.5)
				(thermal_bridge_width 0.5)
				(island_removal_mode 0)
			)
			(polygon
				(pts
					(xy 121.418858 -358.415336) (xy 122.236484 -358.415336) (xy 122.236484 -360.802936) (xy 121.418858 -360.802936)
				)
			)
		)
	)
)
